(kicad_pcb
	(version 20240108)
	(generator "pcbnew")
	(generator_version "8.0")
	(general
		(thickness 1.62)
		(legacy_teardrops no)
	)
	(paper "A4")
	(title_block
		(title "Jetson Orin Baseboard")
		(date "2025-03-12")
		(rev "1.3.4")
		(company "Antmicro Ltd")
		(comment 1 "www.antmicro.com")
		(comment 9 "footprints 444-448 of 677")
	)
	(layers
		(0 "F.Cu" signal)
		(1 "In1.Cu" signal)
		(2 "In2.Cu" signal)
		(3 "In3.Cu" signal)
		(4 "In4.Cu" jumper)
		(5 "In5.Cu" signal)
		(6 "In6.Cu" signal)
		(31 "B.Cu" signal)
		(32 "B.Adhes" user "B.Adhesive")
		(33 "F.Adhes" user "F.Adhesive")
		(34 "B.Paste" user)
		(35 "F.Paste" user)
		(36 "B.SilkS" user "B.Silkscreen")
		(37 "F.SilkS" user "F.Silkscreen")
		(38 "B.Mask" user)
		(39 "F.Mask" user)
		(40 "Dwgs.User" user "User.Drawings")
		(41 "Cmts.User" user "User.Comments")
		(42 "Eco1.User" user "User.Eco1")
		(43 "Eco2.User" user "User.Eco2")
		(44 "Edge.Cuts" user)
		(45 "Margin" user)
		(46 "B.CrtYd" user "B.Courtyard")
		(47 "F.CrtYd" user "F.Courtyard")
		(48 "B.Fab" user)
		(49 "F.Fab" user)
	)
	(footprint "antmicro-footprints:C_0402_1005Metric"
		(layer "B.Cu")
		(at 97.45 90.2)
		(descr "Capacitor SMD 0402")
		(tags "capacitor SMD 0402")
		(property "Reference" "C86"
			(at 3.12 0.06 180)
			(layer "B.SilkS")
			(effects
				(font
					(size 0.7 0.7)
					(thickness 0.15)
				)
				(justify left bottom mirror)
			)
		)
		(property "Value" "C_100n_0402"
			(at 0 -1.4 180)
			(layer "B.Fab")
			(effects
				(font
					(size 0.7 0.7)
					(thickness 0.15)
				)
				(justify left bottom mirror)
			)
		)
		(property "Footprint" "antmicro-footprints:C_0402_1005Metric"
			(at 0 0 0)
			(layer "F.Fab")
			(hide yes)
			(effects
				(font
					(size 1.27 1.27)
					(thickness 0.15)
				)
			)
		)
		(property "Datasheet" "https://www.murata.com/products/productdetail?partno=GRM155R61H104KE14%23"
			(at 0 0 0)
			(layer "F.Fab")
			(hide yes)
			(effects
				(font
					(size 1.27 1.27)
					(thickness 0.15)
				)
			)
		)
		(property "Author" "Antmicro"
			(at 0 0 0)
			(layer "B.Fab")
			(hide yes)
			(effects
				(font
					(size 1 1)
					(thickness 0.15)
				)
				(justify mirror)
			)
		)
		(property "Dielectric" "X5R"
			(at 0 0 0)
			(layer "B.Fab")
			(hide yes)
			(effects
				(font
					(size 1 1)
					(thickness 0.15)
				)
				(justify mirror)
			)
		)
		(property "License" "Apache-2.0"
			(at 0 0 0)
			(layer "B.Fab")
			(hide yes)
			(effects
				(font
					(size 1 1)
					(thickness 0.15)
				)
				(justify mirror)
			)
		)
		(property "MPN" "GRM155R61H104KE14D"
			(at 0 0 0)
			(layer "B.Fab")
			(hide yes)
			(effects
				(font
					(size 1 1)
					(thickness 0.15)
				)
				(justify mirror)
			)
		)
		(property "Manufacturer" "Murata"
			(at 0 0 0)
			(layer "B.Fab")
			(hide yes)
			(effects
				(font
					(size 1 1)
					(thickness 0.15)
				)
				(justify mirror)
			)
		)
		(property "Val" "100n"
			(at 0 0 0)
			(layer "B.Fab")
			(hide yes)
			(effects
				(font
					(size 1 1)
					(thickness 0.15)
				)
				(justify mirror)
			)
		)
		(property "Voltage" "50V"
			(at 0 0 0)
			(layer "B.Fab")
			(hide yes)
			(effects
				(font
					(size 1 1)
					(thickness 0.15)
				)
				(justify mirror)
			)
		)
		(sheetname "HDMI")
		(sheetfile "hdmi.kicad_sch")
		(attr smd)
		(fp_rect
			(start -0.925 0.47)
			(end 0.925 -0.47)
			(stroke
				(width 0.05)
				(type default)
			)
			(fill none)
			(layer "B.CrtYd")
		)
		(fp_line
			(start -0.494 -0.248)
			(end 0.504 -0.248)
			(stroke
				(width 0.15)
				(type solid)
			)
			(layer "B.Fab")
		)
		(fp_line
			(start -0.494 0.25)
			(end -0.494 -0.248)
			(stroke
				(width 0.15)
				(type solid)
			)
			(layer "B.Fab")
		)
		(fp_line
			(start 0.504 -0.248)
			(end 0.504 0.25)
			(stroke
				(width 0.15)
				(type solid)
			)
			(layer "B.Fab")
		)
		(fp_line
			(start 0.504 0.25)
			(end -0.494 0.25)
			(stroke
				(width 0.15)
				(type solid)
			)
			(layer "B.Fab")
		)
		(fp_text user "License: Apache-2.0"
			(at -0.932 -5.17 180)
			(layer "B.Fab")
			(hide yes)
			(effects
				(font
					(size 0.7 0.7)
					(thickness 0.15)
				)
				(justify left bottom mirror)
			)
		)
		(fp_text user "Author: Antmicro"
			(at -0.932 -4.17 180)
			(layer "B.Fab")
			(hide yes)
			(effects
				(font
					(size 0.7 0.7)
					(thickness 0.15)
				)
				(justify left bottom mirror)
			)
		)
		(fp_text user "${REFERENCE}"
			(at -0.932 -3.168 180)
			(layer "B.Fab")
			(hide yes)
			(effects
				(font
					(size 0.7 0.7)
					(thickness 0.15)
				)
				(justify left bottom mirror)
			)
		)
		(pad "1" smd roundrect
			(at -0.48 0)
			(size 0.59 0.64)
			(layers "B.Cu" "B.Paste" "B.Mask")
			(roundrect_rratio 0.25)
			(net 556 "/HDMI/DP_MUX_D0-")
			(pintype "passive")
		)
		(pad "2" smd roundrect
			(at 0.48 0)
			(size 0.59 0.64)
			(layers "B.Cu" "B.Paste" "B.Mask")
			(roundrect_rratio 0.25)
			(net 420 "DP1_TXD3_HDMI_TXC_N")
			(pintype "passive")
		)
	)
	(footprint "antmicro-footprints:XDFN-2_1x0.60mm"
		(layer "B.Cu")
		(at 130.25 94.78)
		(property "Reference" "D22"
			(at -1.05 1.42 180)
			(layer "B.SilkS")
			(effects
				(font
					(size 0.7 0.7)
					(thickness 0.15)
				)
				(justify right bottom mirror)
			)
		)
		(property "Value" "TPD1E0B04_XDFN-2"
			(at 0 -1.5 180)
			(layer "B.Fab")
			(effects
				(font
					(size 0.7 0.7)
					(thickness 0.15)
				)
				(justify left bottom mirror)
			)
		)
		(property "Footprint" "antmicro-footprints:XDFN-2_1x0.60mm"
			(at 0 0 0)
			(layer "F.Fab")
			(hide yes)
			(effects
				(font
					(size 1.27 1.27)
					(thickness 0.15)
				)
			)
		)
		(property "Datasheet" "https://www.ti.com/general/docs/suppproductinfo.tsp?distId=26&gotoUrl=https://www.ti.com/lit/gpn/tpd1e0b04"
			(at 0 0 0)
			(layer "F.Fab")
			(hide yes)
			(effects
				(font
					(size 1.27 1.27)
					(thickness 0.15)
				)
			)
		)
		(property "MPN" "TPD1E0B04DPYR"
			(at 0 0 0)
			(layer "B.Fab")
			(hide yes)
			(effects
				(font
					(size 1 1)
					(thickness 0.15)
				)
				(justify mirror)
			)
		)
		(property "Manufacturer" "Texas Instruments"
			(at 0 0 0)
			(layer "B.Fab")
			(hide yes)
			(effects
				(font
					(size 1 1)
					(thickness 0.15)
				)
				(justify mirror)
			)
		)
		(property "Author" "Antmicro"
			(at 0 0 0)
			(layer "B.Fab")
			(hide yes)
			(effects
				(font
					(size 1 1)
					(thickness 0.15)
				)
				(justify mirror)
			)
		)
		(property "License" "Apache-2.0"
			(at 0 0 0)
			(layer "B.Fab")
			(hide yes)
			(effects
				(font
					(size 1 1)
					(thickness 0.15)
				)
				(justify mirror)
			)
		)
		(sheetname "Peripherals")
		(sheetfile "peripherals.kicad_sch")
		(attr smd)
		(fp_rect
			(start -0.725 0.475)
			(end 0.725 -0.475)
			(stroke
				(width 0.05)
				(type solid)
			)
			(fill none)
			(layer "B.CrtYd")
		)
		(fp_rect
			(start -0.55 0.35)
			(end 0.55 -0.35)
			(stroke
				(width 0.15)
				(type solid)
			)
			(fill none)
			(layer "B.Fab")
		)
		(fp_text user "${REFERENCE}"
			(at -0.8 -3.2 180)
			(layer "B.Fab")
			(hide yes)
			(effects
				(font
					(size 0.7 0.7)
					(thickness 0.15)
				)
				(justify left bottom mirror)
			)
		)
		(fp_text user "License: Apache-2.0"
			(at -0.8 -5.6 180)
			(layer "B.Fab")
			(hide yes)
			(effects
				(font
					(size 0.7 0.7)
					(thickness 0.15)
				)
				(justify left bottom mirror)
			)
		)
		(fp_text user "Author: Antmicro"
			(at -0.8 -4.4 180)
			(layer "B.Fab")
			(hide yes)
			(effects
				(font
					(size 0.7 0.7)
					(thickness 0.15)
				)
				(justify left bottom mirror)
			)
		)
		(pad "1" smd roundrect
			(at -0.351 0)
			(size 0.3 0.5)
			(layers "B.Cu" "B.Paste" "B.Mask")
			(roundrect_rratio 0.25)
			(net 434 "USB1_D_N")
			(pinfunction "C")
			(pintype "passive")
		)
		(pad "2" smd roundrect
			(at 0.349 0)
			(size 0.3 0.5)
			(layers "B.Cu" "B.Paste" "B.Mask")
			(roundrect_rratio 0.25)
			(net 1 "GND")
			(pinfunction "A")
			(pintype "passive")
		)
	)
	(footprint "antmicro-footprints:R_0402_1005Metric"
		(layer "B.Cu")
		(at 106 93.02)
		(descr "Resistor SMD 0402")
		(tags "resistor SMD 0402")
		(property "Reference" "R38"
			(at -0.8 0.43 180)
			(layer "B.SilkS")
			(effects
				(font
					(size 0.7 0.7)
					(thickness 0.15)
				)
				(justify left bottom mirror)
			)
		)
		(property "Value" "R_47k_0402"
			(at 0 -1.4 180)
			(layer "B.Fab")
			(effects
				(font
					(size 0.7 0.7)
					(thickness 0.15)
				)
				(justify left bottom mirror)
			)
		)
		(property "Footprint" "antmicro-footprints:R_0402_1005Metric"
			(at 0 0 0)
			(layer "F.Fab")
			(hide yes)
			(effects
				(font
					(size 1.27 1.27)
					(thickness 0.15)
				)
			)
		)
		(property "Datasheet" "https://www.bourns.com/docs/product-datasheets/cr.pdf"
			(at 0 0 0)
			(layer "F.Fab")
			(hide yes)
			(effects
				(font
					(size 1.27 1.27)
					(thickness 0.15)
				)
			)
		)
		(property "Author" "Antmicro"
			(at 0 0 0)
			(layer "B.Fab")
			(hide yes)
			(effects
				(font
					(size 1 1)
					(thickness 0.15)
				)
				(justify mirror)
			)
		)
		(property "License" "Apache-2.0"
			(at 0 0 0)
			(layer "B.Fab")
			(hide yes)
			(effects
				(font
					(size 1 1)
					(thickness 0.15)
				)
				(justify mirror)
			)
		)
		(property "MPN" "CR0402-FX-4702GLF"
			(at 0 0 0)
			(layer "B.Fab")
			(hide yes)
			(effects
				(font
					(size 1 1)
					(thickness 0.15)
				)
				(justify mirror)
			)
		)
		(property "Manufacturer" "Bourns"
			(at 0 0 0)
			(layer "B.Fab")
			(hide yes)
			(effects
				(font
					(size 1 1)
					(thickness 0.15)
				)
				(justify mirror)
			)
		)
		(property "Tolerance" "1%"
			(at 0 0 0)
			(layer "B.Fab")
			(hide yes)
			(effects
				(font
					(size 1 1)
					(thickness 0.15)
				)
				(justify mirror)
			)
		)
		(property "Val" "47k"
			(at 0 0 0)
			(layer "B.Fab")
			(hide yes)
			(effects
				(font
					(size 1 1)
					(thickness 0.15)
				)
				(justify mirror)
			)
		)
		(sheetname "M.2")
		(sheetfile "m-2.kicad_sch")
		(attr smd exclude_from_pos_files exclude_from_bom dnp)
		(fp_rect
			(start -0.925 0.47)
			(end 0.925 -0.47)
			(stroke
				(width 0.05)
				(type default)
			)
			(fill none)
			(layer "B.CrtYd")
		)
		(fp_rect
			(start -0.5 0.25)
			(end 0.5 -0.25)
			(stroke
				(width 0.15)
				(type solid)
			)
			(fill none)
			(layer "B.Fab")
		)
		(fp_text user "License: Apache-2.0"
			(at -0.95 -5.169 180)
			(layer "B.Fab")
			(hide yes)
			(effects
				(font
					(size 0.7 0.7)
					(thickness 0.15)
				)
				(justify left bottom mirror)
			)
		)
		(fp_text user "Author: Antmicro"
			(at -0.95 -4.169 180)
			(layer "B.Fab")
			(hide yes)
			(effects
				(font
					(size 0.7 0.7)
					(thickness 0.15)
				)
				(justify left bottom mirror)
			)
		)
		(fp_text user "${REFERENCE}"
			(at -0.95 -3.168 180)
			(layer "B.Fab")
			(hide yes)
			(effects
				(font
					(size 0.7 0.7)
					(thickness 0.15)
				)
				(justify left bottom mirror)
			)
		)
		(pad "1" smd roundrect
			(at -0.48 0)
			(size 0.59 0.64)
			(layers "B.Cu" "B.Paste" "B.Mask")
			(roundrect_rratio 0.25)
			(net 87 "+3V3")
			(pintype "passive")
		)
		(pad "2" smd roundrect
			(at 0.48 0)
			(size 0.59 0.64)
			(layers "B.Cu" "B.Paste" "B.Mask")
			(roundrect_rratio 0.25)
			(net 248 "/M.2/~{M2_M_CLKREQ0}")
			(pintype "passive")
		)
	)
	(footprint "antmicro-footprints:R_0402_1005Metric"
		(layer "B.Cu")
		(at 129.9 104.25)
		(descr "Resistor SMD 0402")
		(tags "resistor SMD 0402")
		(property "Reference" "R15"
			(at 1.14 -0.4 180)
			(layer "B.SilkS")
			(effects
				(font
					(size 0.7 0.7)
					(thickness 0.15)
				)
				(justify left bottom mirror)
			)
		)
		(property "Value" "R_0R_0402"
			(at 0 -1.4 180)
			(layer "B.Fab")
			(effects
				(font
					(size 0.7 0.7)
					(thickness 0.15)
				)
				(justify left bottom mirror)
			)
		)
		(property "Footprint" "antmicro-footprints:R_0402_1005Metric"
			(at 0 0 0)
			(layer "F.Fab")
			(hide yes)
			(effects
				(font
					(size 1.27 1.27)
					(thickness 0.15)
				)
			)
		)
		(property "Datasheet" "https://industrial.panasonic.com/cdbs/www-data/pdf/RDA0000/AOA0000C301.pdf"
			(at 0 0 0)
			(layer "F.Fab")
			(hide yes)
			(effects
				(font
					(size 1.27 1.27)
					(thickness 0.15)
				)
			)
		)
		(property "Author" "Antmicro"
			(at 0 0 0)
			(layer "B.Fab")
			(hide yes)
			(effects
				(font
					(size 1 1)
					(thickness 0.15)
				)
				(justify mirror)
			)
		)
		(property "Current" "1A"
			(at 0 0 0)
			(layer "B.Fab")
			(hide yes)
			(effects
				(font
					(size 1 1)
					(thickness 0.15)
				)
				(justify mirror)
			)
		)
		(property "License" "Apache-2.0"
			(at 0 0 0)
			(layer "B.Fab")
			(hide yes)
			(effects
				(font
					(size 1 1)
					(thickness 0.15)
				)
				(justify mirror)
			)
		)
		(property "MPN" "ERJ2GE0R00X"
			(at 0 0 0)
			(layer "B.Fab")
			(hide yes)
			(effects
				(font
					(size 1 1)
					(thickness 0.15)
				)
				(justify mirror)
			)
		)
		(property "Manufacturer" "Panasonic"
			(at 0 0 0)
			(layer "B.Fab")
			(hide yes)
			(effects
				(font
					(size 1 1)
					(thickness 0.15)
				)
				(justify mirror)
			)
		)
		(property "Tolerance" ""
			(at 0 0 0)
			(layer "B.Fab")
			(hide yes)
			(effects
				(font
					(size 1 1)
					(thickness 0.15)
				)
				(justify mirror)
			)
		)
		(property "Val" "0R"
			(at 0 0 0)
			(layer "B.Fab")
			(hide yes)
			(effects
				(font
					(size 1 1)
					(thickness 0.15)
				)
				(justify mirror)
			)
		)
		(sheetname "M.2")
		(sheetfile "m-2.kicad_sch")
		(attr smd)
		(fp_rect
			(start -0.925 0.47)
			(end 0.925 -0.47)
			(stroke
				(width 0.05)
				(type default)
			)
			(fill none)
			(layer "B.CrtYd")
		)
		(fp_rect
			(start -0.5 0.25)
			(end 0.5 -0.25)
			(stroke
				(width 0.15)
				(type solid)
			)
			(fill none)
			(layer "B.Fab")
		)
		(fp_text user "Author: Antmicro"
			(at -0.95 -4.169 180)
			(layer "B.Fab")
			(hide yes)
			(effects
				(font
					(size 0.7 0.7)
					(thickness 0.15)
				)
				(justify left bottom mirror)
			)
		)
		(fp_text user "License: Apache-2.0"
			(at -0.95 -5.169 180)
			(layer "B.Fab")
			(hide yes)
			(effects
				(font
					(size 0.7 0.7)
					(thickness 0.15)
				)
				(justify left bottom mirror)
			)
		)
		(fp_text user "${REFERENCE}"
			(at -0.95 -3.168 180)
			(layer "B.Fab")
			(hide yes)
			(effects
				(font
					(size 0.7 0.7)
					(thickness 0.15)
				)
				(justify left bottom mirror)
			)
		)
		(pad "1" smd roundrect
			(at -0.48 0)
			(size 0.59 0.64)
			(layers "B.Cu" "B.Paste" "B.Mask")
			(roundrect_rratio 0.25)
			(net 453 "PCIE_WAKE*")
			(pintype "passive")
		)
		(pad "2" smd roundrect
			(at 0.48 0)
			(size 0.59 0.64)
			(layers "B.Cu" "B.Paste" "B.Mask")
			(roundrect_rratio 0.25)
			(net 427 "PCIE_WAKE_SEL_EXT")
			(pintype "passive")
		)
	)
	(footprint "antmicro-footprints:R_0402_1005Metric"
		(layer "B.Cu")
		(at 74.75 121.1)
		(descr "Resistor SMD 0402")
		(tags "resistor SMD 0402")
		(property "Reference" "R110"
			(at 3.6 0.4 180)
			(layer "B.SilkS")
			(effects
				(font
					(size 0.7 0.7)
					(thickness 0.15)
				)
				(justify left bottom mirror)
			)
		)
		(property "Value" "R_2M_0402"
			(at 0 -1.4 180)
			(layer "B.Fab")
			(effects
				(font
					(size 0.7 0.7)
					(thickness 0.15)
				)
				(justify left bottom mirror)
			)
		)
		(property "Footprint" "antmicro-footprints:R_0402_1005Metric"
			(at 0 0 0)
			(layer "F.Fab")
			(hide yes)
			(effects
				(font
					(size 1.27 1.27)
					(thickness 0.15)
				)
			)
		)
		(property "Datasheet" "https://www.mouser.com/datasheet/2/447/YAGEO_PYu_RC_Group_51_RoHS_L_12-3313492.pdf"
			(at 0 0 0)
			(layer "F.Fab")
			(hide yes)
			(effects
				(font
					(size 1.27 1.27)
					(thickness 0.15)
				)
			)
		)
		(property "Description" "SMD Chip Resistor, 2 Mohm, ± 1%, 62.5 mW, 0402 [1005 Metric], Thick Film, General Purpose"
			(at 0 0 0)
			(layer "F.Fab")
			(hide yes)
			(effects
				(font
					(size 1.27 1.27)
					(thickness 0.15)
				)
			)
		)
		(property "Author" "Antmicro"
			(at 0 0 0)
			(layer "B.Fab")
			(hide yes)
			(effects
				(font
					(size 1 1)
					(thickness 0.15)
				)
				(justify mirror)
			)
		)
		(property "License" "Apache-2.0"
			(at 0 0 0)
			(layer "B.Fab")
			(hide yes)
			(effects
				(font
					(size 1 1)
					(thickness 0.15)
				)
				(justify mirror)
			)
		)
		(property "MPN" "RC0402FR-072ML"
			(at 0 0 0)
			(layer "B.Fab")
			(hide yes)
			(effects
				(font
					(size 1 1)
					(thickness 0.15)
				)
				(justify mirror)
			)
		)
		(property "Manufacturer" "YAGEO"
			(at 0 0 0)
			(layer "B.Fab")
			(hide yes)
			(effects
				(font
					(size 1 1)
					(thickness 0.15)
				)
				(justify mirror)
			)
		)
		(property "Tolerance" "1%"
			(at 0 0 0)
			(layer "B.Fab")
			(hide yes)
			(effects
				(font
					(size 1 1)
					(thickness 0.15)
				)
				(justify mirror)
			)
		)
		(property "Val" "2M"
			(at 0 0 0)
			(layer "B.Fab")
			(hide yes)
			(effects
				(font
					(size 1 1)
					(thickness 0.15)
				)
				(justify mirror)
			)
		)
		(sheetname "USB Debug, DP")
		(sheetfile "usb.kicad_sch")
		(attr smd)
		(fp_rect
			(start -0.925 0.47)
			(end 0.925 -0.47)
			(stroke
				(width 0.05)
				(type default)
			)
			(fill none)
			(layer "B.CrtYd")
		)
		(fp_rect
			(start -0.5 0.25)
			(end 0.5 -0.25)
			(stroke
				(width 0.15)
				(type solid)
			)
			(fill none)
			(layer "B.Fab")
		)
		(fp_text user "${REFERENCE}"
			(at -0.95 -3.168 180)
			(layer "B.Fab")
			(hide yes)
			(effects
				(font
					(size 0.7 0.7)
					(thickness 0.15)
				)
				(justify left bottom mirror)
			)
		)
		(fp_text user "License: Apache-2.0"
			(at -0.95 -5.169 180)
			(layer "B.Fab")
			(hide yes)
			(effects
				(font
					(size 0.7 0.7)
					(thickness 0.15)
				)
				(justify left bottom mirror)
			)
		)
		(fp_text user "Author: Antmicro"
			(at -0.95 -4.169 180)
			(layer "B.Fab")
			(hide yes)
			(effects
				(font
					(size 0.7 0.7)
					(thickness 0.15)
				)
				(justify left bottom mirror)
			)
		)
		(pad "1" smd roundrect
			(at -0.48 0)
			(size 0.59 0.64)
			(layers "B.Cu" "B.Paste" "B.Mask")
			(roundrect_rratio 0.25)
			(net 614 "/USB Debug, DP/USBC0_SBU_P")
			(pintype "passive")
		)
		(pad "2" smd roundrect
			(at 0.48 0)
			(size 0.59 0.64)
			(layers "B.Cu" "B.Paste" "B.Mask")
			(roundrect_rratio 0.25)
			(net 1 "GND")
			(pintype "passive")
		)
	)
)
